# SCM (Grand Teton) — schematic netlist excerpt (pin names and nets, part order shuffled) for the footprints in the layout excerpt that follows; sources: Cadence DE-HDL packaged netlist, KiCad conversion of 12092022_DA0F0TMDCD0_F0T_Management_Board_D_brd_V3_OCP.brd

C242  Q_CAP  0.1UF 25V 10% X7R  pkg 0402  page 41 : A = VCCIO0 ; B = GND
R37  Q_RES  33.2 1% CHIP  pkg 0402LF  page 13 : A = IRQ_SMI_ACTIVE_GF_N ; B = IRQ_SMI_ACTIVE_BMC_N

(kicad_pcb
	(version 20260206)
	(generator "pcbnew")
	(generator_version "10.0")
	(general
		(thickness 1.6)
		(legacy_teardrops no)
	)
	(paper "A4")
	(title_block
		(title "12092022_DA0F0TMDCD0_F0T_Management_Board_D_brd_V3_OCP.brd")
		(comment 1 "Grand Teton / footprints 1010-1011 of 1440")
	)
	(layers
		(0 "F.Cu" signal "TOP")
		(4 "In1.Cu" signal "GND")
		(6 "In2.Cu" signal "IN1")
		(8 "In3.Cu" signal "GND1")
		(10 "In4.Cu" signal "IN2")
		(12 "In5.Cu" signal "VCC")
		(14 "In6.Cu" signal "VCC1")
		(16 "In7.Cu" signal "IN3")
		(18 "In8.Cu" signal "GND2")
		(20 "In9.Cu" signal "IN4")
		(22 "In10.Cu" signal "GND3")
		(2 "B.Cu" signal "BOTTOM")
		(9 "F.Adhes" user "F.Adhesive")
		(11 "B.Adhes" user "B.Adhesive")
		(13 "F.Paste" user "Package Geometry/Pastemask Top")
		(15 "B.Paste" user "Package Geometry/Pastemask Bottom")
		(5 "F.SilkS" user "Ref Des/Silkscreen Top")
		(7 "B.SilkS" user "Ref Des/Silkscreen Bottom")
		(1 "F.Mask" user "Board Geometry/Soldermask Top")
		(3 "B.Mask" user "Board Geometry/Soldermask Bottom")
		(17 "Dwgs.User" user "User.Drawings")
		(19 "Cmts.User" user "User.Comments")
		(21 "Eco1.User" user "User.Eco1")
		(23 "Eco2.User" user "User.Eco2")
		(25 "Edge.Cuts" user "Board Geometry/Outline")
		(27 "Margin" user)
		(31 "F.CrtYd" user "Package Geometry/Place Bound Top")
		(29 "B.CrtYd" user "Package Geometry/Place Bound Bottom")
		(35 "F.Fab" user "Ref Des/Assembly Top")
		(33 "B.Fab" user "Ref Des/Assembly Bottom")
	)
	(footprint ""
		(layer "B.Cu")
		(at 58.55208 -61.0616 90)
		(property "Reference" "R37"
			(at 0 0 90)
			(layer "B.SilkS")
			(hide yes)
			(effects
				(font
					(size 1.27 1.27)
				)
				(justify mirror)
			)
		)
		(property "Value" ""
			(at 0 0 90)
			(layer "B.Fab")
			(effects
				(font
					(size 1.27 1.27)
				)
				(justify mirror)
			)
		)
		(duplicate_pad_numbers_are_jumpers no)
		(fp_line
			(start 0.7874 -0.4064)
			(end -0.7874 -0.4064)
			(stroke
				(width 0.1524)
				(type default)
			)
			(layer "B.SilkS")
		)
		(fp_line
			(start -0.7874 -0.4064)
			(end -0.7874 0.4064)
			(stroke
				(width 0.1524)
				(type default)
			)
			(layer "B.SilkS")
		)
		(fp_line
			(start 0.7874 0.4064)
			(end 0.7874 -0.4064)
			(stroke
				(width 0.1524)
				(type default)
			)
			(layer "B.SilkS")
		)
		(fp_line
			(start -0.7874 0.4064)
			(end 0.7874 0.4064)
			(stroke
				(width 0.1524)
				(type default)
			)
			(layer "B.SilkS")
		)
		(fp_line
			(start 0.67945 -0.305054)
			(end 0.12065 -0.305054)
			(stroke
				(width 0.1)
				(type default)
			)
			(layer "B.Fab")
		)
		(fp_line
			(start 0.12065 -0.305054)
			(end 0.12065 -0.2794)
			(stroke
				(width 0.1)
				(type default)
			)
			(layer "B.Fab")
		)
		(fp_line
			(start -0.12065 -0.3048)
			(end -0.67945 -0.3048)
			(stroke
				(width 0.1)
				(type default)
			)
			(layer "B.Fab")
		)
		(fp_line
			(start -0.67945 -0.3048)
			(end -0.67945 0.3048)
			(stroke
				(width 0.1)
				(type default)
			)
			(layer "B.Fab")
		)
		(fp_line
			(start 0.12065 -0.2794)
			(end -0.12065 -0.2794)
			(stroke
				(width 0.1)
				(type default)
			)
			(layer "B.Fab")
		)
		(fp_line
			(start -0.12065 -0.2794)
			(end -0.12065 -0.3048)
			(stroke
				(width 0.1)
				(type default)
			)
			(layer "B.Fab")
		)
		(fp_line
			(start 0.12065 0.2794)
			(end 0.12065 0.3048)
			(stroke
				(width 0.1)
				(type default)
			)
			(layer "B.Fab")
		)
		(fp_line
			(start -0.120396 0.2794)
			(end 0.12065 0.2794)
			(stroke
				(width 0.1)
				(type default)
			)
			(layer "B.Fab")
		)
		(fp_line
			(start 0.67945 0.3048)
			(end 0.67945 -0.305054)
			(stroke
				(width 0.1)
				(type default)
			)
			(layer "B.Fab")
		)
		(fp_line
			(start 0.12065 0.3048)
			(end 0.67945 0.3048)
			(stroke
				(width 0.1)
				(type default)
			)
			(layer "B.Fab")
		)
		(fp_line
			(start -0.120396 0.3048)
			(end -0.120396 0.2794)
			(stroke
				(width 0.1)
				(type default)
			)
			(layer "B.Fab")
		)
		(fp_line
			(start -0.67945 0.3048)
			(end -0.120396 0.3048)
			(stroke
				(width 0.1)
				(type default)
			)
			(layer "B.Fab")
		)
		(pad "1" smd circle
			(at 0.40005 0 270)
			(size 0 0)
			(layers "B.Cu" "B.Mask" "B.Paste")
			(net "IRQ_SMI_ACTIVE_GF_N")
		)
		(pad "2" smd circle
			(at -0.40005 0 270)
			(size 0 0)
			(layers "B.Cu" "B.Mask" "B.Paste")
			(net "IRQ_SMI_ACTIVE_BMC_N")
		)
	)
	(footprint ""
		(layer "B.Cu")
		(at 21.301456 -92.4306 -90)
		(property "Reference" "C242"
			(at 0 0 90)
			(layer "B.SilkS")
			(hide yes)
			(effects
				(font
					(size 1.27 1.27)
				)
				(justify mirror)
			)
		)
		(property "Value" ""
			(at 0 0 90)
			(layer "B.Fab")
			(effects
				(font
					(size 1.27 1.27)
				)
				(justify mirror)
			)
		)
		(duplicate_pad_numbers_are_jumpers no)
		(fp_line
			(start -0.69215 0.2921)
			(end 0.69215 0.2921)
			(stroke
				(width 0.1524)
				(type default)
			)
			(layer "B.SilkS")
		)
		(fp_line
			(start 0.69215 0.2921)
			(end 0.69215 -0.2921)
			(stroke
				(width 0.1524)
				(type default)
			)
			(layer "B.SilkS")
		)
		(fp_line
			(start -0.69215 -0.2921)
			(end -0.69215 0.2921)
			(stroke
				(width 0.1524)
				(type default)
			)
			(layer "B.SilkS")
		)
		(fp_line
			(start 0.69215 -0.2921)
			(end -0.69215 -0.2921)
			(stroke
				(width 0.1524)
				(type default)
			)
			(layer "B.SilkS")
		)
		(fp_line
			(start -0.51435 0.2794)
			(end 0.51435 0.2794)
			(stroke
				(width 0.1)
				(type default)
			)
			(layer "B.Fab")
		)
		(fp_line
			(start 0.51435 0.2794)
			(end 0.51435 -0.2794)
			(stroke
				(width 0.1)
				(type default)
			)
			(layer "B.Fab")
		)
		(fp_line
			(start -0.51435 -0.2794)
			(end -0.51435 0.2794)
			(stroke
				(width 0.1)
				(type default)
			)
			(layer "B.Fab")
		)
		(fp_line
			(start 0.51435 -0.2794)
			(end -0.51435 -0.2794)
			(stroke
				(width 0.1)
				(type default)
			)
			(layer "B.Fab")
		)
		(pad "1" smd circle
			(at 0.40005 0 90)
			(size 0 0)
			(layers "B.Cu" "B.Mask" "B.Paste")
			(net "VCCIO0")
		)
		(pad "2" smd circle
			(at -0.40005 0 90)
			(size 0 0)
			(layers "B.Cu" "B.Mask" "B.Paste")
			(net "GND")
		)
		(zone
			(layer "B.Cu")
			(hatch none 0.5)
			(connect_pads
				(clearance 0)
			)
			(min_thickness 0.25)
			(keepout
				(tracks not_allowed)
				(vias allowed)
				(pads allowed)
				(copperpour not_allowed)
				(footprints allowed)
			)
			(placement
				(enabled no)
				(sheetname "")
			)
			(fill
				(thermal_gap 0.5)
				(thermal_bridge_width 0.5)
				(island_removal_mode 0)
			)
			(polygon
				(pts
					(xy 21.213826 -92.2401) (xy 21.15566 -92.33154) (xy 21.15566 -92.53093) (xy 21.213826 -92.6211)
					(xy 21.389086 -92.6211) (xy 21.447506 -92.53093) (xy 21.447506 -92.33154) (xy 21.38934 -92.2401)
				)
			)
		)
	)
)
